(kicad_pcb
	(version 20241229)
	(generator "pcbnew")
	(generator_version "9.0")
	(general
		(thickness 1.552)
		(legacy_teardrops no)
	)
	(paper "A4")
	(title_block
		(date "2023-07-25")
		(rev "1.1.4")
		(comment 9 "footprints 224-227 of 379")
	)
	(layers
		(0 "F.Cu" signal)
		(4 "In1.Cu" signal)
		(6 "In2.Cu" signal)
		(8 "In3.Cu" signal)
		(10 "In4.Cu" signal)
		(12 "In5.Cu" signal)
		(14 "In6.Cu" signal)
		(2 "B.Cu" signal)
		(9 "F.Adhes" user "F.Adhesive")
		(11 "B.Adhes" user "B.Adhesive")
		(13 "F.Paste" user)
		(15 "B.Paste" user)
		(5 "F.SilkS" user "F.Silkscreen")
		(7 "B.SilkS" user "B.Silkscreen")
		(1 "F.Mask" user)
		(3 "B.Mask" user)
		(17 "Dwgs.User" user "User.Drawings")
		(19 "Cmts.User" user "User.Comments")
		(21 "Eco1.User" user "User.Eco1")
		(23 "Eco2.User" user "User.Eco2")
		(25 "Edge.Cuts" user)
		(27 "Margin" user)
		(31 "F.CrtYd" user "F.Courtyard")
		(29 "B.CrtYd" user "B.Courtyard")
		(35 "F.Fab" user)
		(33 "B.Fab" user)
	)
	(footprint "antmicro-footprints:Conn_BNC_031-70526-21"
		(layer "F.Cu")
		(at 68.45 104.85 -90)
		(property "Reference" "J3"
			(at 6.59 -7.08 0)
			(unlocked yes)
			(layer "F.SilkS")
			(effects
				(font
					(size 0.65 0.65)
					(thickness 0.15)
				)
				(justify left bottom)
			)
		)
		(property "Value" "Conn_BNC_031-70526-21"
			(at 0 13.9 270)
			(layer "F.Fab")
			(hide yes)
			(effects
				(font
					(size 0.7 0.7)
					(thickness 0.15)
				)
				(justify left bottom)
			)
		)
		(property "Datasheet" "https://www.farnell.com/cad/2305565.pdf?_ga=2.190633003.1014497200.1574067480-156563690.1566371002&_gac=1.57062104.1572875319.Cj0KCQiAtf_tBRDtARIsAIbAKe0A1M5y_jdFCiNLNrHM5L2GjmDvn_4qnRvhHAD9jBdL9AmoMNThLCoaAjhJEALw_wcB"
			(at 0 0 270)
			(layer "F.Fab")
			(hide yes)
			(effects
				(font
					(size 1.27 1.27)
					(thickness 0.15)
				)
			)
		)
		(property "Description" "RF / Coaxial Connector, BNC Coaxial, Straight Bulkhead Jack, Board Edge / End Launch, 75 ohm"
			(at 0 0 270)
			(layer "F.Fab")
			(hide yes)
			(effects
				(font
					(size 1.27 1.27)
					(thickness 0.15)
				)
			)
		)
		(property "Author" "Antmicro"
			(at -36.4 173.3 0)
			(layer "F.Fab")
			(hide yes)
			(effects
				(font
					(size 1 1)
					(thickness 0.15)
				)
			)
		)
		(property "License" "Apache-2.0"
			(at -36.4 173.3 0)
			(layer "F.Fab")
			(hide yes)
			(effects
				(font
					(size 1 1)
					(thickness 0.15)
				)
			)
		)
		(property "MPN" "031-70526-21"
			(at -36.4 173.3 0)
			(layer "F.Fab")
			(hide yes)
			(effects
				(font
					(size 1 1)
					(thickness 0.15)
				)
			)
		)
		(property "Manufacturer" "Amphenol"
			(at -36.4 173.3 0)
			(layer "F.Fab")
			(hide yes)
			(effects
				(font
					(size 1 1)
					(thickness 0.15)
				)
			)
		)
		(property ki_fp_filters "*BNC* *SMA* *SMB* *SMC* *Cinch*")
		(sheetname "/SDI/")
		(sheetfile "sdi.kicad_sch")
		(attr smd)
		(fp_line
			(start 7.3 12.9)
			(end -7.4 12.9)
			(stroke
				(width 0.05)
				(type solid)
			)
			(layer "B.CrtYd")
		)
		(fp_line
			(start -8.2 -4.6)
			(end -7.4 -4.6)
			(stroke
				(width 0.05)
				(type solid)
			)
			(layer "B.CrtYd")
		)
		(fp_line
			(start -7.4 -4.6)
			(end -7.4 12.9)
			(stroke
				(width 0.05)
				(type solid)
			)
			(layer "B.CrtYd")
		)
		(fp_line
			(start 7.3 -4.6)
			(end 7.3 12.9)
			(stroke
				(width 0.05)
				(type solid)
			)
			(layer "B.CrtYd")
		)
		(fp_line
			(start 8.1 -4.6)
			(end 7.3 -4.6)
			(stroke
				(width 0.05)
				(type solid)
			)
			(layer "B.CrtYd")
		)
		(fp_line
			(start -8.2 -5.5)
			(end -8.2 -4.6)
			(stroke
				(width 0.05)
				(type solid)
			)
			(layer "B.CrtYd")
		)
		(fp_line
			(start -6.6 -5.5)
			(end -8.2 -5.5)
			(stroke
				(width 0.05)
				(type solid)
			)
			(layer "B.CrtYd")
		)
		(fp_line
			(start 6.5 -5.5)
			(end 8.1 -5.5)
			(stroke
				(width 0.05)
				(type solid)
			)
			(layer "B.CrtYd")
		)
		(fp_line
			(start 8.1 -5.5)
			(end 8.1 -4.6)
			(stroke
				(width 0.05)
				(type solid)
			)
			(layer "B.CrtYd")
		)
		(fp_line
			(start -6.6 -6.6)
			(end -6.6 -5.5)
			(stroke
				(width 0.05)
				(type solid)
			)
			(layer "B.CrtYd")
		)
		(fp_line
			(start -5.7 -6.6)
			(end -6.6 -6.6)
			(stroke
				(width 0.05)
				(type solid)
			)
			(layer "B.CrtYd")
		)
		(fp_line
			(start 5.6 -6.6)
			(end 6.5 -6.6)
			(stroke
				(width 0.05)
				(type solid)
			)
			(layer "B.CrtYd")
		)
		(fp_line
			(start 6.5 -6.6)
			(end 6.5 -5.5)
			(stroke
				(width 0.05)
				(type solid)
			)
			(layer "B.CrtYd")
		)
		(fp_line
			(start 4.1 -12.9)
			(end -4.2 -12.9)
			(stroke
				(width 0.05)
				(type solid)
			)
			(layer "B.CrtYd")
		)
		(fp_line
			(start -5.7 -13.6)
			(end -5.7 -6.6)
			(stroke
				(width 0.05)
				(type solid)
			)
			(layer "B.CrtYd")
		)
		(fp_line
			(start -4.2 -13.6)
			(end -4.2 -12.9)
			(stroke
				(width 0.05)
				(type solid)
			)
			(layer "B.CrtYd")
		)
		(fp_line
			(start -4.2 -13.6)
			(end -5.7 -13.6)
			(stroke
				(width 0.05)
				(type solid)
			)
			(layer "B.CrtYd")
		)
		(fp_line
			(start 4.1 -13.6)
			(end 4.1 -12.9)
			(stroke
				(width 0.05)
				(type solid)
			)
			(layer "B.CrtYd")
		)
		(fp_line
			(start 4.1 -13.6)
			(end 5.6 -13.6)
			(stroke
				(width 0.05)
				(type solid)
			)
			(layer "B.CrtYd")
		)
		(fp_line
			(start 5.6 -13.6)
			(end 5.6 -6.6)
			(stroke
				(width 0.05)
				(type solid)
			)
			(layer "B.CrtYd")
		)
		(fp_line
			(start -7.4 12.9)
			(end 7.3 12.9)
			(stroke
				(width 0.05)
				(type solid)
			)
			(layer "F.CrtYd")
		)
		(fp_line
			(start -8.2 -4.6)
			(end -7.4 -4.6)
			(stroke
				(width 0.05)
				(type solid)
			)
			(layer "F.CrtYd")
		)
		(fp_line
			(start -7.4 -4.6)
			(end -7.4 12.9)
			(stroke
				(width 0.05)
				(type solid)
			)
			(layer "F.CrtYd")
		)
		(fp_line
			(start 7.3 -4.6)
			(end 7.3 12.9)
			(stroke
				(width 0.05)
				(type solid)
			)
			(layer "F.CrtYd")
		)
		(fp_line
			(start 8.1 -4.6)
			(end 7.3 -4.6)
			(stroke
				(width 0.05)
				(type solid)
			)
			(layer "F.CrtYd")
		)
		(fp_line
			(start -8.2 -5.5)
			(end -8.2 -4.6)
			(stroke
				(width 0.05)
				(type solid)
			)
			(layer "F.CrtYd")
		)
		(fp_line
			(start -6.6 -5.5)
			(end -8.2 -5.5)
			(stroke
				(width 0.05)
				(type solid)
			)
			(layer "F.CrtYd")
		)
		(fp_line
			(start 6.5 -5.5)
			(end 8.1 -5.5)
			(stroke
				(width 0.05)
				(type solid)
			)
			(layer "F.CrtYd")
		)
		(fp_line
			(start 8.1 -5.5)
			(end 8.1 -4.6)
			(stroke
				(width 0.05)
				(type solid)
			)
			(layer "F.CrtYd")
		)
		(fp_line
			(start -6.6 -6.6)
			(end -6.6 -5.5)
			(stroke
				(width 0.05)
				(type solid)
			)
			(layer "F.CrtYd")
		)
		(fp_line
			(start -5.7 -6.6)
			(end -6.6 -6.6)
			(stroke
				(width 0.05)
				(type solid)
			)
			(layer "F.CrtYd")
		)
		(fp_line
			(start 5.6 -6.6)
			(end 6.5 -6.6)
			(stroke
				(width 0.05)
				(type solid)
			)
			(layer "F.CrtYd")
		)
		(fp_line
			(start 6.5 -6.6)
			(end 6.5 -5.5)
			(stroke
				(width 0.05)
				(type solid)
			)
			(layer "F.CrtYd")
		)
		(fp_line
			(start -4.2 -12.9)
			(end 4.1 -12.9)
			(stroke
				(width 0.05)
				(type solid)
			)
			(layer "F.CrtYd")
		)
		(fp_line
			(start -5.7 -13.6)
			(end -5.7 -6.6)
			(stroke
				(width 0.05)
				(type solid)
			)
			(layer "F.CrtYd")
		)
		(fp_line
			(start -4.2 -13.6)
			(end -4.2 -12.9)
			(stroke
				(width 0.05)
				(type solid)
			)
			(layer "F.CrtYd")
		)
		(fp_line
			(start -4.2 -13.6)
			(end -5.7 -13.6)
			(stroke
				(width 0.05)
				(type solid)
			)
			(layer "F.CrtYd")
		)
		(fp_line
			(start 4.1 -13.6)
			(end 4.1 -12.9)
			(stroke
				(width 0.05)
				(type solid)
			)
			(layer "F.CrtYd")
		)
		(fp_line
			(start 4.1 -13.6)
			(end 5.6 -13.6)
			(stroke
				(width 0.05)
				(type solid)
			)
			(layer "F.CrtYd")
		)
		(fp_line
			(start 5.6 -13.6)
			(end 5.6 -6.6)
			(stroke
				(width 0.05)
				(type solid)
			)
			(layer "F.CrtYd")
		)
		(pad "1" smd rect
			(at 0 -7.872 270)
			(size 1.1 1.75)
			(layers "F.Cu" "F.Mask" "F.Paste")
			(net 252 "/SDI/SDI_OUT")
			(pinfunction "1")
			(pintype "passive")
		)
		(pad "2" smd rect
			(at -4.851 -10.221 270)
			(size 1.1 6.45)
			(layers "F.Cu" "F.Mask" "F.Paste")
			(net 1 "GND")
			(pinfunction "2")
			(pintype "passive")
		)
		(pad "2" smd rect
			(at 4.849 -10.221 270)
			(size 1.1 6.45)
			(layers "F.Cu" "F.Mask" "F.Paste")
			(net 1 "GND")
			(pinfunction "2")
			(pintype "passive")
		)
	)
	(footprint "antmicro-footprints:C_0603_1608Metric"
		(layer "F.Cu")
		(at 161.43 66.49 90)
		(descr "Capacitor SMD 0603")
		(tags "capacitor 0603")
		(property "Reference" "C13"
			(at -2.12 -0.82 180)
			(layer "F.SilkS")
			(effects
				(font
					(size 0.65 0.65)
					(thickness 0.15)
				)
				(justify left bottom)
			)
		)
		(property "Value" "C_10u_0603"
			(at 0 1.6 90)
			(layer "F.Fab")
			(hide yes)
			(effects
				(font
					(size 0.7 0.7)
					(thickness 0.15)
				)
				(justify left bottom)
			)
		)
		(property "Datasheet" "https://www.murata.com/products/productdetail?partno=GRM188R61A106KE69%23"
			(at 0 0 90)
			(layer "F.Fab")
			(hide yes)
			(effects
				(font
					(size 1.27 1.27)
					(thickness 0.15)
				)
			)
		)
		(property "Description" "SMD Multilayer Ceramic Capacitor, 10 µF, 10 V, 0603 [1608 Metric], ± 10%, X5R, GRM Series"
			(at 0 0 90)
			(layer "F.Fab")
			(hide yes)
			(effects
				(font
					(size 1.27 1.27)
					(thickness 0.15)
				)
			)
		)
		(property "Author" "Antmicro"
			(at 227.92 -94.94 0)
			(layer "F.Fab")
			(hide yes)
			(effects
				(font
					(size 1 1)
					(thickness 0.15)
				)
			)
		)
		(property "License" "Apache-2.0"
			(at 227.92 -94.94 0)
			(layer "F.Fab")
			(hide yes)
			(effects
				(font
					(size 1 1)
					(thickness 0.15)
				)
			)
		)
		(property "MPN" "GRM188R61A106KE69D"
			(at 227.92 -94.94 0)
			(layer "F.Fab")
			(hide yes)
			(effects
				(font
					(size 1 1)
					(thickness 0.15)
				)
			)
		)
		(property "Manufacturer" "Murata"
			(at 227.92 -94.94 0)
			(layer "F.Fab")
			(hide yes)
			(effects
				(font
					(size 1 1)
					(thickness 0.15)
				)
			)
		)
		(property "Val" "10u"
			(at 227.92 -94.94 0)
			(layer "F.Fab")
			(hide yes)
			(effects
				(font
					(size 1 1)
					(thickness 0.15)
				)
			)
		)
		(property "Voltage" ""
			(at 227.92 -94.94 0)
			(layer "F.Fab")
			(hide yes)
			(effects
				(font
					(size 1 1)
					(thickness 0.15)
				)
			)
		)
		(property "Dielectric" "template_dielectric"
			(at 0 0 90)
			(unlocked yes)
			(layer "F.Fab")
			(hide yes)
			(effects
				(font
					(size 1 1)
					(thickness 0.15)
				)
			)
		)
		(sheetname "/Power Supply/")
		(sheetfile "supply.kicad_sch")
		(attr smd)
		(fp_line
			(start -0.15 -0.4)
			(end 0.15 -0.4)
			(stroke
				(width 0.15)
				(type solid)
			)
			(layer "F.SilkS")
		)
		(fp_line
			(start -0.15 0.4)
			(end 0.15 0.4)
			(stroke
				(width 0.15)
				(type solid)
			)
			(layer "F.SilkS")
		)
		(fp_rect
			(start -1.25 -0.65)
			(end 1.25 0.65)
			(stroke
				(width 0.05)
				(type solid)
			)
			(fill no)
			(layer "F.CrtYd")
		)
		(fp_rect
			(start -0.8 -0.4)
			(end 0.8 0.4)
			(stroke
				(width 0.15)
				(type solid)
			)
			(fill no)
			(layer "F.Fab")
		)
		(fp_text user "License: Apache-2.0"
			(at -1.682 5.895 90)
			(layer "F.Fab")
			(effects
				(font
					(size 0.7 0.7)
					(thickness 0.15)
				)
				(justify left bottom)
			)
		)
		(fp_text user "Author: Antmicro"
			(at -1.682 4.894 90)
			(layer "F.Fab")
			(effects
				(font
					(size 0.7 0.7)
					(thickness 0.15)
				)
				(justify left bottom)
			)
		)
		(fp_text user "${REFERENCE}"
			(at -1.682 3.895 90)
			(layer "F.Fab")
			(effects
				(font
					(size 0.7 0.7)
					(thickness 0.15)
				)
				(justify left bottom)
			)
		)
		(pad "1" smd roundrect
			(at -0.7 0 90)
			(size 0.8 1)
			(layers "F.Cu" "F.Mask" "F.Paste")
			(roundrect_rratio 0.2)
			(net 328 "/Power Supply/5V_3V3_IN")
			(pintype "passive")
		)
		(pad "2" smd roundrect
			(at 0.7 0 90)
			(size 0.8 1)
			(layers "F.Cu" "F.Mask" "F.Paste")
			(roundrect_rratio 0.2)
			(net 1 "GND")
			(pintype "passive")
		)
	)
	(footprint "antmicro-footprints:TP_SMD_0.75mm"
		(layer "F.Cu")
		(at 139.5908 64.25 90)
		(property "Reference" "TP7"
			(at -2.39 0.3392 90)
			(layer "F.SilkS")
			(effects
				(font
					(size 0.65 0.65)
					(thickness 0.15)
				)
				(justify left bottom)
			)
		)
		(property "Value" "TP_0.75mm_SMD"
			(at 0 1.2 90)
			(layer "F.Fab")
			(hide yes)
			(effects
				(font
					(size 0.7 0.7)
					(thickness 0.15)
				)
				(justify left bottom)
			)
		)
		(property "Description" "SMT test point"
			(at 0 0 90)
			(layer "F.Fab")
			(hide yes)
			(effects
				(font
					(size 1.27 1.27)
					(thickness 0.15)
				)
			)
		)
		(property "Author" "Antmicro"
			(at 203.8408 -75.3408 0)
			(layer "F.Fab")
			(hide yes)
			(effects
				(font
					(size 1 1)
					(thickness 0.15)
				)
			)
		)
		(property "License" "Apache-2.0"
			(at 203.8408 -75.3408 0)
			(layer "F.Fab")
			(hide yes)
			(effects
				(font
					(size 1 1)
					(thickness 0.15)
				)
			)
		)
		(property "MPN" ""
			(at 203.8408 -75.3408 0)
			(layer "F.Fab")
			(hide yes)
			(effects
				(font
					(size 1 1)
					(thickness 0.15)
				)
			)
		)
		(property "Manufacturer" ""
			(at 203.8408 -75.3408 0)
			(layer "F.Fab")
			(hide yes)
			(effects
				(font
					(size 1 1)
					(thickness 0.15)
				)
			)
		)
		(sheetname "/Power Supply/")
		(sheetfile "supply.kicad_sch")
		(attr exclude_from_pos_files)
		(fp_circle
			(center 0 0)
			(end 0.475 0)
			(stroke
				(width 0.05)
				(type default)
			)
			(fill no)
			(layer "F.CrtYd")
		)
		(fp_text user "Author: Antmicro"
			(at -0.4 3.901 90)
			(layer "F.Fab")
			(effects
				(font
					(size 0.7 0.7)
					(thickness 0.15)
				)
				(justify left bottom)
			)
		)
		(fp_text user "License: Apache-2.0"
			(at -0.4 5.101 90)
			(layer "F.Fab")
			(effects
				(font
					(size 0.7 0.7)
					(thickness 0.15)
				)
				(justify left bottom)
			)
		)
		(fp_text user "${REFERENCE}"
			(at -0.4 2.7 90)
			(layer "F.Fab")
			(effects
				(font
					(size 0.7 0.7)
					(thickness 0.15)
				)
				(justify left bottom)
			)
		)
		(pad "1" smd circle
			(at 0 0 90)
			(size 0.75 0.75)
			(layers "F.Cu" "F.Mask")
			(net 248 "+1V5")
			(pinfunction "1")
			(pintype "passive")
		)
	)
	(footprint "antmicro-footprints:C_0603_1608Metric"
		(layer "F.Cu")
		(at 161.23 63.94 90)
		(descr "Capacitor SMD 0603")
		(tags "capacitor 0603")
		(property "Reference" "C22"
			(at 0.11 -2.48 180)
			(layer "F.SilkS")
			(effects
				(font
					(size 0.65 0.65)
					(thickness 0.15)
				)
				(justify left bottom)
			)
		)
		(property "Value" "C_22u_0603"
			(at 0 1.6 90)
			(layer "F.Fab")
			(hide yes)
			(effects
				(font
					(size 0.7 0.7)
					(thickness 0.15)
				)
				(justify left bottom)
			)
		)
		(property "Datasheet" "https://www.murata.com/products/productdetail?partno=GRM188R60J226MEA0%23"
			(at 0 0 90)
			(layer "F.Fab")
			(hide yes)
			(effects
				(font
					(size 1.27 1.27)
					(thickness 0.15)
				)
			)
		)
		(property "Description" "SMD Multilayer Ceramic Capacitor, 22 µF, 6.3 V, 0603 [1608 Metric], ± 20%, X5R, GRM Series"
			(at 0 0 90)
			(layer "F.Fab")
			(hide yes)
			(effects
				(font
					(size 1.27 1.27)
					(thickness 0.15)
				)
			)
		)
		(property "Author" "Antmicro"
			(at 225.17 -97.29 0)
			(layer "F.Fab")
			(hide yes)
			(effects
				(font
					(size 1 1)
					(thickness 0.15)
				)
			)
		)
		(property "Dielectric" ""
			(at 225.17 -97.29 0)
			(layer "F.Fab")
			(hide yes)
			(effects
				(font
					(size 1 1)
					(thickness 0.15)
				)
			)
		)
		(property "License" "Apache-2.0"
			(at 225.17 -97.29 0)
			(layer "F.Fab")
			(hide yes)
			(effects
				(font
					(size 1 1)
					(thickness 0.15)
				)
			)
		)
		(property "MPN" "GRM188R60J226MEA0D"
			(at 225.17 -97.29 0)
			(layer "F.Fab")
			(hide yes)
			(effects
				(font
					(size 1 1)
					(thickness 0.15)
				)
			)
		)
		(property "Manufacturer" "Murata"
			(at 225.17 -97.29 0)
			(layer "F.Fab")
			(hide yes)
			(effects
				(font
					(size 1 1)
					(thickness 0.15)
				)
			)
		)
		(property "Val" "22u"
			(at 225.17 -97.29 0)
			(layer "F.Fab")
			(hide yes)
			(effects
				(font
					(size 1 1)
					(thickness 0.15)
				)
			)
		)
		(property "Voltage" ""
			(at 225.17 -97.29 0)
			(layer "F.Fab")
			(hide yes)
			(effects
				(font
					(size 1 1)
					(thickness 0.15)
				)
			)
		)
		(sheetname "/Power Supply/")
		(sheetfile "supply.kicad_sch")
		(attr smd)
		(fp_line
			(start -0.15 -0.4)
			(end 0.15 -0.4)
			(stroke
				(width 0.15)
				(type solid)
			)
			(layer "F.SilkS")
		)
		(fp_line
			(start -0.15 0.4)
			(end 0.15 0.4)
			(stroke
				(width 0.15)
				(type solid)
			)
			(layer "F.SilkS")
		)
		(fp_rect
			(start -1.25 -0.65)
			(end 1.25 0.65)
			(stroke
				(width 0.05)
				(type solid)
			)
			(fill no)
			(layer "F.CrtYd")
		)
		(fp_rect
			(start -0.8 -0.4)
			(end 0.8 0.4)
			(stroke
				(width 0.15)
				(type solid)
			)
			(fill no)
			(layer "F.Fab")
		)
		(fp_text user "License: Apache-2.0"
			(at -1.682 5.895 90)
			(layer "F.Fab")
			(effects
				(font
					(size 0.7 0.7)
					(thickness 0.15)
				)
				(justify left bottom)
			)
		)
		(fp_text user "${REFERENCE}"
			(at -1.682 3.895 90)
			(layer "F.Fab")
			(effects
				(font
					(size 0.7 0.7)
					(thickness 0.15)
				)
				(justify left bottom)
			)
		)
		(fp_text user "Author: Antmicro"
			(at -1.682 4.894 90)
			(layer "F.Fab")
			(effects
				(font
					(size 0.7 0.7)
					(thickness 0.15)
				)
				(justify left bottom)
			)
		)
		(pad "1" smd roundrect
			(at -0.7 0 90)
			(size 0.8 1)
			(layers "F.Cu" "F.Mask" "F.Paste")
			(roundrect_rratio 0.2)
			(net 1 "GND")
			(pintype "passive")
		)
		(pad "2" smd roundrect
			(at 0.7 0 90)
			(size 0.8 1)
			(layers "F.Cu" "F.Mask" "F.Paste")
			(roundrect_rratio 0.2)
			(net 275 "/Power Supply/3V3_OUT")
			(pintype "passive")
		)
	)
)
